FILE_TYPE = CONNECTIVITY;
{Allegro Design Entry HDL 16.6-p007 (v16-6-112F) 10/10/2012}
"PAGE_NUMBER" = 107;
0"NC";
1"P3E_CPU0_PE1_SS_RXN<7:0>";
2"P3E_CPU0_PE1_SS_TXP<7:0>";
3"P3E_CPU0_PE1_PCH_TXN<7:0>";
4"P3E_CPU0_PE1_SS_TXN<7:0>";
5"P3E_CPU0_PE1_SS_C_TXN<7:0>";
6"P3E_CPU0_PE1_SS_TXP<7:0>";
7"P3E_CPU0_PE1_SS_RXN<7:0>";
8"P3E_CPU0_PE1_SS_R_RXP<7:0>";
9"P3E_CPU0_PE1_SS_C_TXP<7:0>";
10"P3E_CPU0_PE1_SS_RXP<7:0>";
11"P3E_CPU0_PE1_SS_R_RXN<7:0>";
12"P3E_CPU0_PE1_SS_TXN<7:0>";
13"P3E_CPU0_PE1_PCH_RXN<7:0>";
14"P3E_CPU0_PE1_PCH_TXP<7:0>";
15"P3E_CPU0_PE1_SS_RXP<7:0>";
16"P3E_CPU0_PE1_PCH_RXP<7:0>";
17"P3E_CPU0_PE1_PCH_RXP<1>";
18"P3E_CPU0_PE1_SS_RXP<2>";
19"P3E_CPU0_PE1_SS_RXP<4>";
20"P3E_CPU0_PE1_SS_RXP<3>";
21"P3E_CPU0_PE1_SS_RXP<5>";
22"P3E_CPU0_PE1_SS_TXP<1>";
23"P3E_CPU0_PE1_SS_TXN<1>";
24"P3E_CPU0_PE1_SS_TXN<1>";
25"P3E_CPU0_PE1_SS_R_RXN<0>";
26"P3E_CPU0_PE1_SS_R_RXN<1>";
27"P3E_CPU0_PE1_SS_RXN<2>";
28"P3E_CPU0_PE1_SS_R_RXN<5>";
29"P3E_CPU0_PE1_SS_R_RXN<4>";
30"P3E_CPU0_PE1_SS_R_RXP<2>";
31"P3E_CPU0_PE1_SS_R_RXP<6>";
32"P3E_CPU0_PE1_SS_RXP<5>";
33"P3E_CPU0_PE1_SS_R_RXP<4>";
34"P3E_CPU0_PE1_SS_RXP<3>";
35"P3E_CPU0_PE1_SS_RXP<1>";
36"P3E_CPU0_PE1_SS_R_RXP<0>";
37"P3E_CPU0_PE1_SS_RXN<7>";
38"P3E_CPU0_PE1_SS_R_RXN<6>";
39"P3E_CPU0_PE1_SS_RXN<3>";
40"P3E_CPU0_PE1_SS_R_RXN<3>";
41"P3E_CPU0_PE1_SS_R_RXN<2>";
42"P3E_CPU0_PE1_SS_TXN<0>";
43"P3E_CPU0_PE1_SS_TXN<2>";
44"P3E_CPU0_PE1_SS_C_TXN<4>";
45"P3E_CPU0_PE1_SS_TXN<4>";
46"P3E_CPU0_PE1_SS_TXN<6>";
47"P3E_CPU0_PE1_SS_C_TXN<5>";
48"P3E_CPU0_PE1_SS_C_TXN<7>";
49"P3E_CPU0_PE1_PCH_TXP<7>";
50"P3E_CPU0_PE1_PCH_TXP<6>";
51"P3E_CPU0_PE1_PCH_TXP<5>";
52"P3E_CPU0_PE1_PCH_TXP<4>";
53"P3E_CPU0_PE1_SS_TXP<7>";
54"P3E_CPU0_PE1_SS_TXP<6>";
55"P3E_CPU0_PE1_SS_TXP<4>";
56"P3E_CPU0_PE1_PCH_TXN<7>";
57"P3E_CPU0_PE1_SS_TXN<7>";
58"P3E_CPU0_PE1_SS_TXN<6>";
59"P3E_CPU0_PE1_PCH_TXP<3>";
60"P3E_CPU0_PE1_PCH_TXP<1>";
61"P3E_CPU0_PE1_PCH_TXP<2>";
62"P3E_CPU0_PE1_SS_TXP<0>";
63"P3E_CPU0_PE1_PCH_TXN<3>";
64"P3E_CPU0_PE1_PCH_TXN<1>";
65"P3E_CPU0_PE1_SS_TXN<2>";
66"P3E_CPU0_PE1_PCH_RXP<7>";
67"P3E_CPU0_PE1_SS_RXN<3>";
68"P3E_CPU0_PE1_SS_RXN<5>";
69"P3E_CPU0_PE1_SS_RXN<7>";
70"P3E_CPU0_PE1_PCH_TXN<5>";
71"P3E_CPU0_PE1_SS_TXP<3>";
72"P3E_CPU0_PE1_SS_TXP<5>";
73"P3E_CPU0_PE1_SS_TXN<5>";
74"P3E_CPU0_PE1_SS_TXN<4>";
75"P3E_CPU0_PE1_SS_TXN<3>";
76"P3E_CPU0_PE1_SS_TXN<5>";
77"P3E_CPU0_PE1_SS_TXN<3>";
78"P3E_CPU0_PE1_SS_TXP<0>";
79"P3E_CPU0_PE1_SS_C_TXN<1>";
80"P3E_CPU0_PE1_SS_C_TXP<1>";
81"P3E_CPU0_PE1_SS_C_TXP<0>";
82"P3E_CPU0_PE1_SS_C_TXP<2>";
83"P3E_CPU0_PE1_SS_C_TXP<3>";
84"P3E_CPU0_PE1_SS_TXP<4>";
85"P3E_CPU0_PE1_SS_TXP<5>";
86"P3E_CPU0_PE1_SS_C_TXP<5>";
87"P3E_CPU0_PE1_SS_TXP<6>";
88"P3E_CPU0_PE1_SS_C_TXP<6>";
89"P3E_CPU0_PE1_SS_C_TXP<7>";
90"P3E_CPU0_PE1_SS_RXN<1>";
91"P3E_CPU0_PE1_SS_RXN<6>";
92"P3E_CPU0_PE1_SS_RXP<7>";
93"P3E_CPU0_PE1_PCH_RXN<3>";
94"P3E_CPU0_PE1_PCH_RXN<0>";
95"P3E_CPU0_PE1_PCH_RXN<6>";
96"P3E_CPU0_PE1_PCH_RXN<2>";
97"P3E_CPU0_PE1_PCH_RXN<4>";
98"P3E_CPU0_PE1_PCH_RXN<1>";
99"P3E_CPU0_PE1_SS_RXN<2>";
100"P3E_CPU0_PE1_PCH_RXN<5>";
101"P3E_CPU0_PE1_PCH_RXP<0>";
102"P3E_CPU0_PE1_PCH_RXP<6>";
103"P3E_CPU0_PE1_PCH_RXP<4>";
104"P3E_CPU0_PE1_PCH_RXP<2>";
105"P3E_CPU0_PE1_SS_RXP<0>";
106"P3E_CPU0_PE1_SS_RXP<1>";
107"P3E_CPU0_PE1_PCH_RXP<3>";
108"P3E_CPU0_PE1_PCH_RXP<5>";
109"P3E_CPU0_PE1_SS_RXP<6>";
110"P3E_CPU0_PE1_SS_RXP<7>";
111"P3E_CPU0_PE1_PCH_TXP<0>";
112"P3E_CPU0_PE1_PCH_RXN<7>";
113"P3E_CPU0_PE1_SS_RXP<0>";
114"P3E_CPU0_PE1_SS_RXP<4>";
115"P3E_CPU0_PE1_SS_R_RXP<5>";
116"P3E_CPU0_PE1_SS_R_RXP<3>";
117"P3E_CPU0_PE1_SS_C_TXN<3>";
118"P3E_CPU0_PE1_SS_C_TXN<6>";
119"P3E_CPU0_PE1_SS_TXN<7>";
120"P3E_CPU0_PE1_SS_RXP<6>";
121"P3E_CPU0_PE1_SS_R_RXN<7>";
122"P3E_CPU0_PE1_SS_RXN<0>";
123"P3E_CPU0_PE1_SS_RXP<2>";
124"P3E_CPU0_PE1_SS_R_RXP<1>";
125"P3E_CPU0_PE1_SS_TXP<7>";
126"P3E_CPU0_PE1_SS_C_TXP<4>";
127"P3E_CPU0_PE1_SS_R_RXP<7>";
128"P3E_CPU0_PE1_SS_C_TXN<2>";
129"P3E_CPU0_PE1_SS_RXN<5>";
130"P3E_CPU0_PE1_SS_RXN<4>";
131"P3E_CPU0_PE1_SS_TXP<2>";
132"P3E_CPU0_PE1_SS_TXP<3>";
133"P3E_CPU0_PE1_SS_TXP<1>";
134"P3E_CPU0_PE1_SS_C_TXN<0>";
135"P3E_CPU0_PE1_SS_TXN<0>";
136"P3E_CPU0_PE1_PCH_TXN<4>";
137"P3E_CPU0_PE1_PCH_TXN<2>";
138"P3E_CPU0_PE1_SS_RXN<4>";
139"P3E_CPU0_PE1_SS_RXN<6>";
140"P3E_CPU0_PE1_PCH_TXN<0>";
141"P3E_CPU0_PE1_PCH_TXN<6>";
142"P3E_CPU0_PE1_SS_TXP<2>";
143"P3E_CPU0_PE1_SS_RXN<1>";
144"P3E_CPU0_PE1_SS_RXN<0>";
%"TAP"
"3","(-5525,2125)","0","mstr_standard","I198";
;
CDS_LIB"mstr_standard"
BODY_TYPE"PLUMBING"
HDL_TAP"TRUE";
"B \NAC \NWC"4;
"S \NAC"
BN"0"135;
%"TAP"
"3","(-5725,2125)","0","mstr_standard","I199";
;
CDS_LIB"mstr_standard"
BODY_TYPE"PLUMBING"
HDL_TAP"TRUE";
"B \NAC \NWC"4;
"S \NAC"
BN"1"23;
%"TAP"
"3","(-5925,2125)","0","mstr_standard","I200";
;
CDS_LIB"mstr_standard"
BODY_TYPE"PLUMBING"
HDL_TAP"TRUE";
"B \NAC \NWC"4;
"S \NAC"
BN"2"65;
%"TAP"
"3","(-6125,2125)","0","mstr_standard","I201";
;
CDS_LIB"mstr_standard"
BODY_TYPE"PLUMBING"
HDL_TAP"TRUE";
"B \NAC \NWC"4;
"S \NAC"
BN"3"75;
%"TAP"
"3","(-6325,2125)","0","mstr_standard","I202";
;
CDS_LIB"mstr_standard"
BODY_TYPE"PLUMBING"
HDL_TAP"TRUE";
"B \NAC \NWC"4;
"S \NAC"
BN"4"74;
%"TAP"
"3","(-6525,2125)","0","mstr_standard","I203";
;
CDS_LIB"mstr_standard"
BODY_TYPE"PLUMBING"
HDL_TAP"TRUE";
"B \NAC \NWC"4;
"S \NAC"
BN"5"73;
%"TAP"
"3","(-6725,2125)","0","mstr_standard","I204";
;
CDS_LIB"mstr_standard"
BODY_TYPE"PLUMBING"
HDL_TAP"TRUE";
"B \NAC \NWC"4;
"S \NAC"
BN"6"58;
%"TAP"
"3","(-6925,2125)","0","mstr_standard","I205";
;
CDS_LIB"mstr_standard"
BODY_TYPE"PLUMBING"
HDL_TAP"TRUE";
"B \NAC \NWC"4;
"S \NAC"
BN"7"57;
%"CAP"
"1","(-5525,1875)","2","mstr_discrete","I207";
;
GROUP"PCIE_UPLINK"
TOLERANCE"10%"
LOCATION"C3P13"
VALUE"0.22UF"
VOLTAGE"16V"
PACK_TYPE"0402"
MATERIAL"X7R"
PART_NUMBER"A36096-155"
CDS_LIB"mstr_discrete"
CDS_LOCATION"C3P13"
CDS_SEC"1"
$SEC"1";
"A"
$PN"1"135;
"B"
$PN"2"140;
%"CAP"
"1","(-5725,1575)","2","mstr_discrete","I208";
;
PART_NUMBER"A36096-155"
TOLERANCE"10%"
MATERIAL"X7R"
VALUE"0.22UF"
VOLTAGE"16V"
PACK_TYPE"0402"
LOCATION"C3P17"
GROUP"PCIE_UPLINK"
CDS_LIB"mstr_discrete"
CDS_SEC"1"
$SEC"1"
CDS_LOCATION"C3P17";
"A"
$PN"1"23;
"B"
$PN"2"64;
%"TAP"
"7","(-5525,1325)","0","mstr_standard","I210";
;
CDS_LIB"mstr_standard"
BODY_TYPE"PLUMBING"
HDL_TAP"TRUE";
"B \NAC \NWC"3;
"S \NAC"
BN"0"140;
%"TAP"
"3","(-5475,1125)","0","mstr_standard","I211";
;
CDS_LIB"mstr_standard"
BODY_TYPE"PLUMBING"
HDL_TAP"TRUE";
"B \NAC \NWC"2;
"S \NAC"
BN"0"62;
%"CAP"
"1","(-5475,875)","2","mstr_discrete","I212";
;
VOLTAGE"16V"
VALUE"0.22UF"
PART_NUMBER"A36096-155"
PACK_TYPE"0402"
TOLERANCE"10%"
MATERIAL"X7R"
LOCATION"C3P11"
GROUP"PCIE_UPLINK"
CDS_LIB"mstr_discrete"
CDS_LOCATION"C3P11"
CDS_SEC"1"
$SEC"1";
"A"
$PN"1"62;
"B"
$PN"2"111;
%"TAP"
"7","(-5725,1325)","0","mstr_standard","I213";
;
CDS_LIB"mstr_standard"
BODY_TYPE"PLUMBING"
HDL_TAP"TRUE";
"B \NAC \NWC"3;
"S \NAC"
BN"1"64;
%"TAP"
"3","(-5675,1125)","0","mstr_standard","I214";
;
CDS_LIB"mstr_standard"
BODY_TYPE"PLUMBING"
HDL_TAP"TRUE";
"B \NAC \NWC"2;
"S \NAC"
BN"1"22;
%"CAP"
"1","(-5925,1900)","2","mstr_discrete","I215";
;
PACK_TYPE"0402"
VOLTAGE"16V"
PART_NUMBER"A36096-155"
MATERIAL"X7R"
TOLERANCE"10%"
VALUE"0.22UF"
LOCATION"C3P20"
GROUP"PCIE_UPLINK"
CDS_LOCATION"C3P20"
CDS_LIB"mstr_discrete"
CDS_SEC"1"
$SEC"1";
"A"
$PN"1"65;
"B"
$PN"2"137;
%"CAP"
"1","(-6125,1575)","2","mstr_discrete","I216";
;
MATERIAL"X7R"
VALUE"0.22UF"
LOCATION"C3P25"
PACK_TYPE"0402"
VOLTAGE"16V"
PART_NUMBER"A36096-155"
TOLERANCE"10%"
GROUP"PCIE_UPLINK"
CDS_LOCATION"C3P25"
$SEC"1"
CDS_SEC"1"
CDS_LIB"mstr_discrete";
"A"
$PN"1"75;
"B"
$PN"2"63;
%"TAP"
"7","(-5925,1325)","0","mstr_standard","I217";
;
CDS_LIB"mstr_standard"
BODY_TYPE"PLUMBING"
HDL_TAP"TRUE";
"B \NAC \NWC"3;
"S \NAC"
BN"2"137;
%"TAP"
"3","(-5875,1125)","0","mstr_standard","I218";
;
CDS_LIB"mstr_standard"
BODY_TYPE"PLUMBING"
HDL_TAP"TRUE";
"B \NAC \NWC"2;
"S \NAC"
BN"2"142;
%"CAP"
"1","(-5875,875)","2","mstr_discrete","I219";
;
LOCATION"C3P18"
PART_NUMBER"A36096-155"
PACK_TYPE"0402"
MATERIAL"X7R"
VOLTAGE"16V"
TOLERANCE"10%"
VALUE"0.22UF"
GROUP"PCIE_UPLINK"
CDS_LOCATION"C3P18"
CDS_LIB"mstr_discrete"
$SEC"1"
CDS_SEC"1";
"A"
$PN"1"142;
"B"
$PN"2"61;
%"TAP"
"3","(-6075,1125)","0","mstr_standard","I220";
;
CDS_LIB"mstr_standard"
BODY_TYPE"PLUMBING"
HDL_TAP"TRUE";
"B \NAC \NWC"2;
"S \NAC"
BN"3"71;
%"TAP"
"7","(-6125,1325)","0","mstr_standard","I221";
;
CDS_LIB"mstr_standard"
BODY_TYPE"PLUMBING"
HDL_TAP"TRUE";
"B \NAC \NWC"3;
"S \NAC"
BN"3"63;
%"TAP"
"3","(-6275,1125)","0","mstr_standard","I222";
;
CDS_LIB"mstr_standard"
BODY_TYPE"PLUMBING"
HDL_TAP"TRUE";
"B \NAC \NWC"2;
"S \NAC"
BN"4"55;
%"CAP"
"1","(-6275,875)","2","mstr_discrete","I223";
;
LOCATION"C3P27"
VALUE"0.22UF"
TOLERANCE"10%"
VOLTAGE"16V"
PACK_TYPE"0402"
PART_NUMBER"A36096-155"
MATERIAL"X7R"
GROUP"PCIE_UPLINK"
CDS_LIB"mstr_discrete"
CDS_LOCATION"C3P27"
CDS_SEC"1"
$SEC"1";
"A"
$PN"1"55;
"B"
$PN"2"52;
%"TAP"
"7","(-5475,325)","0","mstr_standard","I224";
;
CDS_LIB"mstr_standard"
BODY_TYPE"PLUMBING"
HDL_TAP"TRUE";
"B \NAC \NWC"14;
"S \NAC"
BN"0"111;
%"CAP"
"1","(-5675,575)","2","mstr_discrete","I226";
;
PART_NUMBER"A36096-155"
PACK_TYPE"0402"
MATERIAL"X7R"
VALUE"0.22UF"
VOLTAGE"16V"
TOLERANCE"10%"
LOCATION"C3P15"
GROUP"PCIE_UPLINK"
CDS_LIB"mstr_discrete"
CDS_LOCATION"C3P15"
$SEC"1"
CDS_SEC"1";
"A"
$PN"1"22;
"B"
$PN"2"60;
%"TAP"
"7","(-5675,325)","0","mstr_standard","I227";
;
CDS_LIB"mstr_standard"
BODY_TYPE"PLUMBING"
HDL_TAP"TRUE";
"B \NAC \NWC"14;
"S \NAC"
BN"1"60;
%"TAP"
"7","(-5875,325)","0","mstr_standard","I228";
;
CDS_LIB"mstr_standard"
BODY_TYPE"PLUMBING"
HDL_TAP"TRUE";
"B \NAC \NWC"14;
"S \NAC"
BN"2"61;
%"CAP"
"1","(-6075,575)","2","mstr_discrete","I229";
;
LOCATION"C3P23"
PART_NUMBER"A36096-155"
VALUE"0.22UF"
TOLERANCE"10%"
PACK_TYPE"0402"
VOLTAGE"16V"
MATERIAL"X7R"
GROUP"PCIE_UPLINK"
CDS_LOCATION"C3P23"
CDS_LIB"mstr_discrete"
$SEC"1"
CDS_SEC"1";
"A"
$PN"1"71;
"B"
$PN"2"59;
%"TAP"
"7","(-6075,325)","0","mstr_standard","I230";
;
CDS_LIB"mstr_standard"
BODY_TYPE"PLUMBING"
HDL_TAP"TRUE";
"B \NAC \NWC"14;
"S \NAC"
BN"3"59;
%"TAP"
"7","(-6275,325)","0","mstr_standard","I231";
;
CDS_LIB"mstr_standard"
BODY_TYPE"PLUMBING"
HDL_TAP"TRUE";
"B \NAC \NWC"14;
"S \NAC"
BN"4"52;
%"CAP"
"1","(-6325,1875)","2","mstr_discrete","I232";
;
TOLERANCE"10%"
VOLTAGE"16V"
MATERIAL"X7R"
PART_NUMBER"A36096-155"
PACK_TYPE"0402"
VALUE"0.22UF"
LOCATION"C3P28"
GROUP"PCIE_UPLINK"
CDS_LOCATION"C3P28"
CDS_LIB"mstr_discrete"
CDS_SEC"1"
$SEC"1";
"A"
$PN"1"74;
"B"
$PN"2"136;
%"TAP"
"7","(-6325,1325)","0","mstr_standard","I233";
;
CDS_LIB"mstr_standard"
BODY_TYPE"PLUMBING"
HDL_TAP"TRUE";
"B \NAC \NWC"3;
"S \NAC"
BN"4"136;
%"CAP"
"1","(-6525,1575)","2","mstr_discrete","I234";
;
MATERIAL"X7R"
LOCATION"C3P32"
PACK_TYPE"0402"
TOLERANCE"10%"
PART_NUMBER"A36096-155"
VALUE"0.22UF"
VOLTAGE"16V"
GROUP"PCIE_UPLINK"
$SEC"1"
CDS_SEC"1"
CDS_LIB"mstr_discrete"
CDS_LOCATION"C3P32";
"A"
$PN"1"73;
"B"
$PN"2"70;
%"CAP"
"1","(-6725,1875)","2","mstr_discrete","I235";
;
LOCATION"C3P37"
PART_NUMBER"A36096-155"
VALUE"0.22UF"
PACK_TYPE"0402"
MATERIAL"X7R"
VOLTAGE"16V"
TOLERANCE"10%"
GROUP"PCIE_UPLINK"
CDS_LOCATION"C3P37"
CDS_LIB"mstr_discrete"
CDS_SEC"1"
$SEC"1";
"A"
$PN"1"58;
"B"
$PN"2"141;
%"TAP"
"7","(-6525,1325)","0","mstr_standard","I236";
;
CDS_LIB"mstr_standard"
BODY_TYPE"PLUMBING"
HDL_TAP"TRUE";
"B \NAC \NWC"3;
"S \NAC"
BN"5"70;
%"TAP"
"3","(-6475,1125)","0","mstr_standard","I237";
;
CDS_LIB"mstr_standard"
BODY_TYPE"PLUMBING"
HDL_TAP"TRUE";
"B \NAC \NWC"2;
"S \NAC"
BN"5"72;
%"TAP"
"3","(-6675,1125)","0","mstr_standard","I238";
;
CDS_LIB"mstr_standard"
BODY_TYPE"PLUMBING"
HDL_TAP"TRUE";
"B \NAC \NWC"2;
"S \NAC"
BN"6"54;
%"TAP"
"7","(-6725,1325)","0","mstr_standard","I239";
;
CDS_LIB"mstr_standard"
BODY_TYPE"PLUMBING"
HDL_TAP"TRUE";
"B \NAC \NWC"3;
"S \NAC"
BN"6"141;
%"CAP"
"1","(-6675,875)","2","mstr_discrete","I240";
;
PART_NUMBER"A36096-155"
PACK_TYPE"0402"
MATERIAL"X7R"
VOLTAGE"16V"
TOLERANCE"10%"
VALUE"0.22UF"
LOCATION"C3P35"
GROUP"PCIE_UPLINK"
CDS_LOCATION"C3P35"
CDS_LIB"mstr_discrete"
$SEC"1"
CDS_SEC"1";
"A"
$PN"1"54;
"B"
$PN"2"50;
%"CAP"
"1","(-6925,1575)","2","mstr_discrete","I241";
;
PART_NUMBER"A36096-155"
PACK_TYPE"0402"
TOLERANCE"10%"
VOLTAGE"16V"
VALUE"0.22UF"
LOCATION"C3P40"
MATERIAL"X7R"
GROUP"PCIE_UPLINK"
CDS_LOCATION"C3P40"
$SEC"1"
CDS_LIB"mstr_discrete"
CDS_SEC"1";
"A"
$PN"1"57;
"B"
$PN"2"56;
%"TAP"
"7","(-6925,1325)","0","mstr_standard","I242";
;
CDS_LIB"mstr_standard"
BODY_TYPE"PLUMBING"
HDL_TAP"TRUE";
"B \NAC \NWC"3;
"S \NAC"
BN"7"56;
%"TAP"
"3","(-6875,1125)","0","mstr_standard","I243";
;
CDS_LIB"mstr_standard"
BODY_TYPE"PLUMBING"
HDL_TAP"TRUE";
"B \NAC \NWC"2;
"S \NAC"
BN"7"53;
%"CAP"
"1","(-6475,575)","2","mstr_discrete","I245";
;
LOCATION"C3P30"
PART_NUMBER"A36096-155"
VALUE"0.22UF"
MATERIAL"X7R"
PACK_TYPE"0402"
VOLTAGE"16V"
TOLERANCE"10%"
GROUP"PCIE_UPLINK"
CDS_LIB"mstr_discrete"
$SEC"1"
CDS_SEC"1"
CDS_LOCATION"C3P30";
"A"
$PN"1"72;
"B"
$PN"2"51;
%"TAP"
"7","(-6475,325)","0","mstr_standard","I246";
;
CDS_LIB"mstr_standard"
BODY_TYPE"PLUMBING"
HDL_TAP"TRUE";
"B \NAC \NWC"14;
"S \NAC"
BN"5"51;
%"TAP"
"7","(-6675,325)","0","mstr_standard","I247";
;
CDS_LIB"mstr_standard"
BODY_TYPE"PLUMBING"
HDL_TAP"TRUE";
"B \NAC \NWC"14;
"S \NAC"
BN"6"50;
%"CAP"
"1","(-6875,575)","2","mstr_discrete","I248";
;
PART_NUMBER"A36096-155"
MATERIAL"X7R"
PACK_TYPE"0402"
VOLTAGE"16V"
TOLERANCE"10%"
VALUE"0.22UF"
LOCATION"C3P39"
GROUP"PCIE_UPLINK"
CDS_LOCATION"C3P39"
CDS_SEC"1"
$SEC"1"
CDS_LIB"mstr_discrete";
"A"
$PN"1"53;
"B"
$PN"2"49;
%"TAP"
"7","(-6875,325)","0","mstr_standard","I249";
;
CDS_LIB"mstr_standard"
BODY_TYPE"PLUMBING"
HDL_TAP"TRUE";
"B \NAC \NWC"14;
"S \NAC"
BN"7"49;
%"TAP"
"3","(-1950,2075)","0","mstr_standard","I250";
;
CDS_LIB"mstr_standard"
BODY_TYPE"PLUMBING"
HDL_TAP"TRUE";
"B \NAC \NWC"13;
"S \NAC"
BN"0"94;
%"TAP"
"3","(-2150,2075)","0","mstr_standard","I251";
;
CDS_LIB"mstr_standard"
BODY_TYPE"PLUMBING"
HDL_TAP"TRUE";
"B \NAC \NWC"13;
"S \NAC"
BN"1"98;
%"TAP"
"3","(-2350,2075)","0","mstr_standard","I252";
;
CDS_LIB"mstr_standard"
BODY_TYPE"PLUMBING"
HDL_TAP"TRUE";
"B \NAC \NWC"13;
"S \NAC"
BN"2"96;
%"TAP"
"3","(-2550,2075)","0","mstr_standard","I253";
;
CDS_LIB"mstr_standard"
BODY_TYPE"PLUMBING"
HDL_TAP"TRUE";
"B \NAC \NWC"13;
"S \NAC"
BN"3"93;
%"TAP"
"3","(-2750,2075)","0","mstr_standard","I254";
;
CDS_LIB"mstr_standard"
BODY_TYPE"PLUMBING"
HDL_TAP"TRUE";
"B \NAC \NWC"13;
"S \NAC"
BN"4"97;
%"CAP"
"1","(-1950,1875)","2","mstr_discrete","I257";
;
CDS_SEC"1"
GROUP"PCIE_UPLINK"
PART_NUMBER"A36096-155"
LOCATION"C2U4"
VALUE"0.22UF"
VOLTAGE"16V"
TOLERANCE"10%"
MATERIAL"X7R"
PACK_TYPE"0402"
SEC"1"
SEC_TYPE"0402"
CDS_LIB"mstr_discrete"
CDS_LOCATION"C2U4";
"A"
$PN"1"94;
"B"
$PN"2"144;
%"TAP"
"3","(-1900,1075)","0","mstr_standard","I258";
;
CDS_LIB"mstr_standard"
BODY_TYPE"PLUMBING"
HDL_TAP"TRUE";
"B \NAC \NWC"16;
"S \NAC"
BN"0"101;
%"TAP"
"7","(-1950,1275)","0","mstr_standard","I259";
;
CDS_LIB"mstr_standard"
BODY_TYPE"PLUMBING"
HDL_TAP"TRUE";
"B \NAC \NWC"1;
"S \NAC"
BN"0"144;
%"CAP"
"1","(-2150,1525)","2","mstr_discrete","I260";
;
CDS_SEC"1"
PART_NUMBER"A36096-155"
VOLTAGE"16V"
VALUE"0.22UF"
PACK_TYPE"0402"
MATERIAL"X7R"
TOLERANCE"10%"
LOCATION"C2U6"
GROUP"PCIE_UPLINK"
CDS_LIB"mstr_discrete"
SEC_TYPE"0402"
SEC"1"
CDS_LOCATION"C2U6";
"A"
$PN"1"98;
"B"
$PN"2"143;
%"TAP"
"3","(-2100,1075)","0","mstr_standard","I261";
;
CDS_LIB"mstr_standard"
BODY_TYPE"PLUMBING"
HDL_TAP"TRUE";
"B \NAC \NWC"16;
"S \NAC"
BN"1"17;
%"TAP"
"7","(-2150,1275)","0","mstr_standard","I262";
;
CDS_LIB"mstr_standard"
BODY_TYPE"PLUMBING"
HDL_TAP"TRUE";
"B \NAC \NWC"1;
"S \NAC"
BN"1"143;
%"TAP"
"3","(-2300,1075)","0","mstr_standard","I263";
;
CDS_LIB"mstr_standard"
BODY_TYPE"PLUMBING"
HDL_TAP"TRUE";
"B \NAC \NWC"16;
"S \NAC"
BN"2"104;
%"CAP"
"1","(-2350,1875)","2","mstr_discrete","I264";
;
CDS_SEC"1"
GROUP"PCIE_UPLINK"
PART_NUMBER"A36096-155"
LOCATION"C2U8"
PACK_TYPE"0402"
MATERIAL"X7R"
VALUE"0.22UF"
VOLTAGE"16V"
TOLERANCE"10%"
SEC"1"
SEC_TYPE"0402"
CDS_LOCATION"C2U8"
CDS_LIB"mstr_discrete";
"A"
$PN"1"96;
"B"
$PN"2"99;
%"CAP"
"1","(-2750,1875)","2","mstr_discrete","I265";
;
CDS_SEC"1"
GROUP"PCIE_UPLINK"
VALUE"0.22UF"
MATERIAL"X7R"
PACK_TYPE"0402"
VOLTAGE"16V"
PART_NUMBER"A36096-155"
TOLERANCE"10%"
LOCATION"C2U12"
SEC"1"
SEC_TYPE"0402"
CDS_LIB"mstr_discrete"
CDS_LOCATION"C2U12";
"A"
$PN"1"97;
"B"
$PN"2"138;
%"TAP"
"7","(-2350,1275)","0","mstr_standard","I266";
;
CDS_LIB"mstr_standard"
BODY_TYPE"PLUMBING"
HDL_TAP"TRUE";
"B \NAC \NWC"1;
"S \NAC"
BN"2"99;
%"CAP"
"1","(-2550,1525)","2","mstr_discrete","I267";
;
CDS_SEC"1"
PACK_TYPE"0402"
VALUE"0.22UF"
MATERIAL"X7R"
TOLERANCE"10%"
VOLTAGE"16V"
LOCATION"C2U10"
PART_NUMBER"A36096-155"
GROUP"PCIE_UPLINK"
CDS_LOCATION"C2U10"
SEC"1"
SEC_TYPE"0402"
CDS_LIB"mstr_discrete";
"A"
$PN"1"93;
"B"
$PN"2"67;
%"TAP"
"7","(-2550,1275)","0","mstr_standard","I268";
;
CDS_LIB"mstr_standard"
BODY_TYPE"PLUMBING"
HDL_TAP"TRUE";
"B \NAC \NWC"1;
"S \NAC"
BN"3"67;
%"TAP"
"3","(-2500,1075)","0","mstr_standard","I269";
;
CDS_LIB"mstr_standard"
BODY_TYPE"PLUMBING"
HDL_TAP"TRUE";
"B \NAC \NWC"16;
"S \NAC"
BN"3"107;
%"TAP"
"3","(-2700,1075)","0","mstr_standard","I270";
;
CDS_LIB"mstr_standard"
BODY_TYPE"PLUMBING"
HDL_TAP"TRUE";
"B \NAC \NWC"16;
"S \NAC"
BN"4"103;
%"TAP"
"7","(-2750,1275)","0","mstr_standard","I271";
;
CDS_LIB"mstr_standard"
BODY_TYPE"PLUMBING"
HDL_TAP"TRUE";
"B \NAC \NWC"1;
"S \NAC"
BN"4"138;
%"CAP"
"1","(-1900,875)","2","mstr_discrete","I272";
;
CDS_SEC"1"
PACK_TYPE"0402"
LOCATION"C2U3"
TOLERANCE"10%"
VALUE"0.22UF"
MATERIAL"X7R"
VOLTAGE"16V"
PART_NUMBER"A36096-155"
GROUP"PCIE_UPLINK"
SEC"1"
SEC_TYPE"0402"
CDS_LOCATION"C2U3"
CDS_LIB"mstr_discrete";
"A"
$PN"1"101;
"B"
$PN"2"105;
%"TAP"
"7","(-1900,275)","0","mstr_standard","I273";
;
CDS_LIB"mstr_standard"
BODY_TYPE"PLUMBING"
HDL_TAP"TRUE";
"B \NAC \NWC"15;
"S \NAC"
BN"0"105;
%"CAP"
"1","(-2100,525)","2","mstr_discrete","I274";
;
CDS_SEC"1"
MATERIAL"X7R"
PACK_TYPE"0402"
TOLERANCE"10%"
PART_NUMBER"A36096-155"
VOLTAGE"16V"
LOCATION"C2U5"
VALUE"0.22UF"
GROUP"PCIE_UPLINK"
CDS_LIB"mstr_discrete"
SEC_TYPE"0402"
CDS_LOCATION"C2U5"
SEC"1";
"A"
$PN"1"17;
"B"
$PN"2"106;
%"TAP"
"7","(-2100,275)","0","mstr_standard","I275";
;
CDS_LIB"mstr_standard"
BODY_TYPE"PLUMBING"
HDL_TAP"TRUE";
"B \NAC \NWC"15;
"S \NAC"
BN"1"106;
%"TAP"
"7","(-2300,275)","0","mstr_standard","I276";
;
CDS_LIB"mstr_standard"
BODY_TYPE"PLUMBING"
HDL_TAP"TRUE";
"B \NAC \NWC"15;
"S \NAC"
BN"2"18;
%"CAP"
"1","(-2300,875)","2","mstr_discrete","I277";
;
CDS_SEC"1"
TOLERANCE"10%"
PACK_TYPE"0402"
MATERIAL"X7R"
LOCATION"C2U7"
VALUE"0.22UF"
VOLTAGE"16V"
GROUP"PCIE_UPLINK"
PART_NUMBER"A36096-155"
SEC_TYPE"0402"
SEC"1"
CDS_LIB"mstr_discrete"
CDS_LOCATION"C2U7";
"A"
$PN"1"104;
"B"
$PN"2"18;
%"CAP"
"1","(-2700,875)","2","mstr_discrete","I278";
;
CDS_SEC"1"
PACK_TYPE"0402"
LOCATION"C2U11"
TOLERANCE"10%"
VOLTAGE"16V"
MATERIAL"X7R"
VALUE"0.22UF"
PART_NUMBER"A36096-155"
GROUP"PCIE_UPLINK"
SEC"1"
SEC_TYPE"0402"
CDS_LIB"mstr_discrete"
CDS_LOCATION"C2U11";
"A"
$PN"1"103;
"B"
$PN"2"19;
%"CAP"
"1","(-2500,525)","2","mstr_discrete","I279";
;
CDS_SEC"1"
VALUE"0.22UF"
LOCATION"C2U9"
TOLERANCE"10%"
PACK_TYPE"0402"
MATERIAL"X7R"
VOLTAGE"16V"
PART_NUMBER"A36096-155"
GROUP"PCIE_UPLINK"
CDS_LOCATION"C2U9"
CDS_LIB"mstr_discrete"
SEC_TYPE"0402"
SEC"1";
"A"
$PN"1"107;
"B"
$PN"2"20;
%"TAP"
"7","(-2500,275)","0","mstr_standard","I280";
;
CDS_LIB"mstr_standard"
BODY_TYPE"PLUMBING"
HDL_TAP"TRUE";
"B \NAC \NWC"15;
"S \NAC"
BN"3"20;
%"TAP"
"7","(-2700,275)","0","mstr_standard","I281";
;
CDS_LIB"mstr_standard"
BODY_TYPE"PLUMBING"
HDL_TAP"TRUE";
"B \NAC \NWC"15;
"S \NAC"
BN"4"19;
%"TAP"
"3","(-2950,2075)","0","mstr_standard","I282";
;
CDS_LIB"mstr_standard"
BODY_TYPE"PLUMBING"
HDL_TAP"TRUE";
"B \NAC \NWC"13;
"S \NAC"
BN"5"100;
%"TAP"
"3","(-3150,2075)","0","mstr_standard","I283";
;
CDS_LIB"mstr_standard"
BODY_TYPE"PLUMBING"
HDL_TAP"TRUE";
"B \NAC \NWC"13;
"S \NAC"
BN"6"95;
%"TAP"
"3","(-3350,2075)","0","mstr_standard","I284";
;
CDS_LIB"mstr_standard"
BODY_TYPE"PLUMBING"
HDL_TAP"TRUE";
"B \NAC \NWC"13;
"S \NAC"
BN"7"112;
%"CAP"
"1","(-3150,1875)","2","mstr_discrete","I286";
;
CDS_SEC"1"
GROUP"PCIE_UPLINK"
PACK_TYPE"0402"
TOLERANCE"10%"
VOLTAGE"16V"
MATERIAL"X7R"
LOCATION"C2U16"
VALUE"0.22UF"
PART_NUMBER"A36096-155"
SEC"1"
SEC_TYPE"0402"
CDS_LIB"mstr_discrete"
CDS_LOCATION"C2U16";
"A"
$PN"1"95;
"B"
$PN"2"139;
%"CAP"
"1","(-2950,1525)","2","mstr_discrete","I287";
;
CDS_SEC"1"
GROUP"PCIE_UPLINK"
MATERIAL"X7R"
PART_NUMBER"A36096-155"
LOCATION"C2U14"
VOLTAGE"16V"
VALUE"0.22UF"
PACK_TYPE"0402"
TOLERANCE"10%"
CDS_LIB"mstr_discrete"
CDS_LOCATION"C2U14"
SEC"1"
SEC_TYPE"0402";
"A"
$PN"1"100;
"B"
$PN"2"68;
%"TAP"
"3","(-2900,1075)","0","mstr_standard","I288";
;
CDS_LIB"mstr_standard"
BODY_TYPE"PLUMBING"
HDL_TAP"TRUE";
"B \NAC \NWC"16;
"S \NAC"
BN"5"108;
%"TAP"
"7","(-2950,1275)","0","mstr_standard","I289";
;
CDS_LIB"mstr_standard"
BODY_TYPE"PLUMBING"
HDL_TAP"TRUE";
"B \NAC \NWC"1;
"S \NAC"
BN"5"68;
%"TAP"
"7","(-3150,1275)","0","mstr_standard","I290";
;
CDS_LIB"mstr_standard"
BODY_TYPE"PLUMBING"
HDL_TAP"TRUE";
"B \NAC \NWC"1;
"S \NAC"
BN"6"139;
%"TAP"
"3","(-3100,1075)","0","mstr_standard","I291";
;
CDS_LIB"mstr_standard"
BODY_TYPE"PLUMBING"
HDL_TAP"TRUE";
"B \NAC \NWC"16;
"S \NAC"
BN"6"102;
%"TAP"
"7","(-3350,1275)","0","mstr_standard","I292";
;
CDS_LIB"mstr_standard"
BODY_TYPE"PLUMBING"
HDL_TAP"TRUE";
"B \NAC \NWC"1;
"S \NAC"
BN"7"69;
%"TAP"
"3","(-3300,1075)","0","mstr_standard","I293";
;
CDS_LIB"mstr_standard"
BODY_TYPE"PLUMBING"
HDL_TAP"TRUE";
"B \NAC \NWC"16;
"S \NAC"
BN"7"66;
%"CAP"
"1","(-3350,1525)","2","mstr_discrete","I294";
;
CDS_SEC"1"
GROUP"PCIE_UPLINK"
PART_NUMBER"A36096-155"
VALUE"0.22UF"
PACK_TYPE"0402"
MATERIAL"X7R"
TOLERANCE"10%"
VOLTAGE"16V"
LOCATION"C2U18"
CDS_LIB"mstr_discrete"
CDS_LOCATION"C2U18"
SEC_TYPE"0402"
SEC"1";
"A"
$PN"1"112;
"B"
$PN"2"69;
%"CAP"
"1","(-3100,875)","2","mstr_discrete","I296";
;
CDS_SEC"1"
PART_NUMBER"A36096-155"
LOCATION"C2U15"
PACK_TYPE"0402"
TOLERANCE"10%"
VOLTAGE"16V"
VALUE"0.22UF"
MATERIAL"X7R"
GROUP"PCIE_UPLINK"
SEC_TYPE"0402"
SEC"1"
CDS_LOCATION"C2U15"
CDS_LIB"mstr_discrete";
"A"
$PN"1"102;
"B"
$PN"2"109;
%"CAP"
"1","(-2900,525)","2","mstr_discrete","I297";
;
CDS_SEC"1"
PACK_TYPE"0402"
MATERIAL"X7R"
TOLERANCE"10%"
VOLTAGE"16V"
VALUE"0.22UF"
LOCATION"C2U13"
PART_NUMBER"A36096-155"
GROUP"PCIE_UPLINK"
SEC"1"
SEC_TYPE"0402"
CDS_LIB"mstr_discrete"
CDS_LOCATION"C2U13";
"A"
$PN"1"108;
"B"
$PN"2"21;
%"TAP"
"7","(-2900,275)","0","mstr_standard","I298";
;
CDS_LIB"mstr_standard"
BODY_TYPE"PLUMBING"
HDL_TAP"TRUE";
"B \NAC \NWC"15;
"S \NAC"
BN"5"21;
%"TAP"
"7","(-3100,275)","0","mstr_standard","I299";
;
CDS_LIB"mstr_standard"
BODY_TYPE"PLUMBING"
HDL_TAP"TRUE";
"B \NAC \NWC"15;
"S \NAC"
BN"6"109;
%"CAP"
"1","(-3300,525)","2","mstr_discrete","I300";
;
CDS_SEC"1"
MATERIAL"X7R"
PACK_TYPE"0402"
VALUE"0.22UF"
LOCATION"C2U17"
PART_NUMBER"A36096-155"
TOLERANCE"10%"
VOLTAGE"16V"
GROUP"PCIE_UPLINK"
CDS_LOCATION"C2U17"
SEC"1"
SEC_TYPE"0402"
CDS_LIB"mstr_discrete";
"A"
$PN"1"66;
"B"
$PN"2"110;
%"TAP"
"7","(-3300,275)","0","mstr_standard","I301";
;
CDS_LIB"mstr_standard"
BODY_TYPE"PLUMBING"
HDL_TAP"TRUE";
"B \NAC \NWC"15;
"S \NAC"
BN"7"110;
%"TAP"
"3","(-825,4375)","0","mstr_standard","I355";
;
CDS_LIB"mstr_standard"
BODY_TYPE"PLUMBING"
HDL_TAP"TRUE";
"B \NAC \NWC"11;
"S \NAC"
BN"0"25;
%"TAP"
"3","(-1025,4375)","0","mstr_standard","I356";
;
CDS_LIB"mstr_standard"
BODY_TYPE"PLUMBING"
HDL_TAP"TRUE";
"B \NAC \NWC"11;
"S \NAC"
BN"1"26;
%"TAP"
"3","(-1225,4375)","0","mstr_standard","I357";
;
CDS_LIB"mstr_standard"
BODY_TYPE"PLUMBING"
HDL_TAP"TRUE";
"B \NAC \NWC"11;
"S \NAC"
BN"2"41;
%"TAP"
"3","(-1425,4375)","0","mstr_standard","I359";
;
CDS_LIB"mstr_standard"
BODY_TYPE"PLUMBING"
HDL_TAP"TRUE";
"B \NAC \NWC"11;
"S \NAC"
BN"3"40;
%"TAP"
"3","(-1625,4375)","0","mstr_standard","I360";
;
CDS_LIB"mstr_standard"
BODY_TYPE"PLUMBING"
HDL_TAP"TRUE";
"B \NAC \NWC"11;
"S \NAC"
BN"4"29;
%"TAP"
"3","(-1825,4375)","0","mstr_standard","I361";
;
CDS_LIB"mstr_standard"
BODY_TYPE"PLUMBING"
HDL_TAP"TRUE";
"B \NAC \NWC"11;
"S \NAC"
BN"5"28;
%"TAP"
"3","(-2025,4375)","0","mstr_standard","I363";
;
CDS_LIB"mstr_standard"
BODY_TYPE"PLUMBING"
HDL_TAP"TRUE";
"B \NAC \NWC"11;
"S \NAC"
BN"6"38;
%"TAP"
"3","(-2225,4375)","0","mstr_standard","I365";
;
CDS_LIB"mstr_standard"
BODY_TYPE"PLUMBING"
HDL_TAP"TRUE";
"B \NAC \NWC"11;
"S \NAC"
BN"7"121;
%"TAP"
"7","(-825,3575)","0","mstr_standard","I367";
;
CDS_LIB"mstr_standard"
BODY_TYPE"PLUMBING"
HDL_TAP"TRUE";
"B \NAC \NWC"7;
"S \NAC"
BN"0"122;
%"TAP"
"7","(-1025,3575)","0","mstr_standard","I371";
;
CDS_LIB"mstr_standard"
BODY_TYPE"PLUMBING"
HDL_TAP"TRUE";
"B \NAC \NWC"7;
"S \NAC"
BN"1"90;
%"TAP"
"7","(-1225,3575)","0","mstr_standard","I372";
;
CDS_LIB"mstr_standard"
BODY_TYPE"PLUMBING"
HDL_TAP"TRUE";
"B \NAC \NWC"7;
"S \NAC"
BN"2"27;
%"TAP"
"3","(-800,3350)","0","mstr_standard","I373";
;
CDS_LIB"mstr_standard"
BODY_TYPE"PLUMBING"
HDL_TAP"TRUE";
"B \NAC \NWC"8;
"S \NAC"
BN"0"36;
%"TAP"
"3","(-1000,3350)","0","mstr_standard","I375";
;
CDS_LIB"mstr_standard"
BODY_TYPE"PLUMBING"
HDL_TAP"TRUE";
"B \NAC \NWC"8;
"S \NAC"
BN"1"124;
%"TAP"
"3","(-1200,3350)","0","mstr_standard","I376";
;
CDS_LIB"mstr_standard"
BODY_TYPE"PLUMBING"
HDL_TAP"TRUE";
"B \NAC \NWC"8;
"S \NAC"
BN"2"30;
%"TAP"
"7","(-1425,3575)","0","mstr_standard","I379";
;
CDS_LIB"mstr_standard"
BODY_TYPE"PLUMBING"
HDL_TAP"TRUE";
"B \NAC \NWC"7;
"S \NAC"
BN"3"39;
%"TAP"
"7","(-1625,3575)","0","mstr_standard","I380";
;
CDS_LIB"mstr_standard"
BODY_TYPE"PLUMBING"
HDL_TAP"TRUE";
"B \NAC \NWC"7;
"S \NAC"
BN"4"130;
%"TAP"
"7","(-1825,3575)","0","mstr_standard","I382";
;
CDS_LIB"mstr_standard"
BODY_TYPE"PLUMBING"
HDL_TAP"TRUE";
"B \NAC \NWC"7;
"S \NAC"
BN"5"129;
%"TAP"
"3","(-1400,3350)","0","mstr_standard","I383";
;
CDS_LIB"mstr_standard"
BODY_TYPE"PLUMBING"
HDL_TAP"TRUE";
"B \NAC \NWC"8;
"S \NAC"
BN"3"116;
%"TAP"
"3","(-1600,3350)","0","mstr_standard","I384";
;
CDS_LIB"mstr_standard"
BODY_TYPE"PLUMBING"
HDL_TAP"TRUE";
"B \NAC \NWC"8;
"S \NAC"
BN"4"33;
%"TAP"
"7","(-800,2550)","0","mstr_standard","I386";
;
CDS_LIB"mstr_standard"
BODY_TYPE"PLUMBING"
HDL_TAP"TRUE";
"B \NAC \NWC"10;
"S \NAC"
BN"0"113;
%"TAP"
"7","(-1000,2550)","0","mstr_standard","I388";
;
CDS_LIB"mstr_standard"
BODY_TYPE"PLUMBING"
HDL_TAP"TRUE";
"B \NAC \NWC"10;
"S \NAC"
BN"1"35;
%"TAP"
"7","(-1200,2550)","0","mstr_standard","I389";
;
CDS_LIB"mstr_standard"
BODY_TYPE"PLUMBING"
HDL_TAP"TRUE";
"B \NAC \NWC"10;
"S \NAC"
BN"2"123;
%"TAP"
"7","(-1400,2550)","0","mstr_standard","I391";
;
CDS_LIB"mstr_standard"
BODY_TYPE"PLUMBING"
HDL_TAP"TRUE";
"B \NAC \NWC"10;
"S \NAC"
BN"3"34;
%"TAP"
"7","(-1600,2550)","0","mstr_standard","I392";
;
CDS_LIB"mstr_standard"
BODY_TYPE"PLUMBING"
HDL_TAP"TRUE";
"B \NAC \NWC"10;
"S \NAC"
BN"4"114;
%"TAP"
"7","(-2025,3575)","0","mstr_standard","I393";
;
CDS_LIB"mstr_standard"
BODY_TYPE"PLUMBING"
HDL_TAP"TRUE";
"B \NAC \NWC"7;
"S \NAC"
BN"6"91;
%"TAP"
"7","(-2225,3575)","0","mstr_standard","I395";
;
CDS_LIB"mstr_standard"
BODY_TYPE"PLUMBING"
HDL_TAP"TRUE";
"B \NAC \NWC"7;
"S \NAC"
BN"7"37;
%"TAP"
"3","(-1800,3350)","0","mstr_standard","I396";
;
CDS_LIB"mstr_standard"
BODY_TYPE"PLUMBING"
HDL_TAP"TRUE";
"B \NAC \NWC"8;
"S \NAC"
BN"5"115;
%"TAP"
"3","(-2000,3350)","0","mstr_standard","I397";
;
CDS_LIB"mstr_standard"
BODY_TYPE"PLUMBING"
HDL_TAP"TRUE";
"B \NAC \NWC"8;
"S \NAC"
BN"6"31;
%"TAP"
"3","(-2200,3350)","0","mstr_standard","I399";
;
CDS_LIB"mstr_standard"
BODY_TYPE"PLUMBING"
HDL_TAP"TRUE";
"B \NAC \NWC"8;
"S \NAC"
BN"7"127;
%"TAP"
"7","(-1800,2550)","0","mstr_standard","I402";
;
CDS_LIB"mstr_standard"
BODY_TYPE"PLUMBING"
HDL_TAP"TRUE";
"B \NAC \NWC"10;
"S \NAC"
BN"5"32;
%"TAP"
"7","(-2000,2550)","0","mstr_standard","I403";
;
CDS_LIB"mstr_standard"
BODY_TYPE"PLUMBING"
HDL_TAP"TRUE";
"B \NAC \NWC"10;
"S \NAC"
BN"6"120;
%"TAP"
"7","(-2200,2550)","0","mstr_standard","I405";
;
CDS_LIB"mstr_standard"
BODY_TYPE"PLUMBING"
HDL_TAP"TRUE";
"B \NAC \NWC"10;
"S \NAC"
BN"7"92;
%"TAP"
"7","(-5450,2425)","0","mstr_standard","I406";
;
CDS_LIB"mstr_standard"
BODY_TYPE"PLUMBING"
HDL_TAP"TRUE";
"B \NAC \NWC"9;
"S \NAC"
BN"6"88;
%"TAP"
"3","(-4300,4225)","0","mstr_standard","I407";
;
CDS_LIB"mstr_standard"
BODY_TYPE"PLUMBING"
HDL_TAP"TRUE";
"B \NAC \NWC"12;
"S \NAC"
BN"0"42;
%"TAP"
"3","(-4500,4225)","0","mstr_standard","I408";
;
CDS_LIB"mstr_standard"
BODY_TYPE"PLUMBING"
HDL_TAP"TRUE";
"B \NAC \NWC"12;
"S \NAC"
BN"1"24;
%"TAP"
"3","(-4700,4225)","0","mstr_standard","I409";
;
CDS_LIB"mstr_standard"
BODY_TYPE"PLUMBING"
HDL_TAP"TRUE";
"B \NAC \NWC"12;
"S \NAC"
BN"2"43;
%"TAP"
"3","(-4900,4225)","0","mstr_standard","I410";
;
CDS_LIB"mstr_standard"
BODY_TYPE"PLUMBING"
HDL_TAP"TRUE";
"B \NAC \NWC"12;
"S \NAC"
BN"3"77;
%"TAP"
"3","(-5100,4225)","0","mstr_standard","I411";
;
CDS_LIB"mstr_standard"
BODY_TYPE"PLUMBING"
HDL_TAP"TRUE";
"B \NAC \NWC"12;
"S \NAC"
BN"4"45;
%"TAP"
"3","(-5300,4225)","0","mstr_standard","I412";
;
CDS_LIB"mstr_standard"
BODY_TYPE"PLUMBING"
HDL_TAP"TRUE";
"B \NAC \NWC"12;
"S \NAC"
BN"5"76;
%"TAP"
"3","(-5500,4225)","0","mstr_standard","I413";
;
CDS_LIB"mstr_standard"
BODY_TYPE"PLUMBING"
HDL_TAP"TRUE";
"B \NAC \NWC"12;
"S \NAC"
BN"6"46;
%"TAP"
"3","(-5700,4225)","0","mstr_standard","I414";
;
CDS_LIB"mstr_standard"
BODY_TYPE"PLUMBING"
HDL_TAP"TRUE";
"B \NAC \NWC"12;
"S \NAC"
BN"7"119;
%"TAP"
"7","(-4300,3425)","0","mstr_standard","I418";
;
CDS_LIB"mstr_standard"
BODY_TYPE"PLUMBING"
HDL_TAP"TRUE";
"B \NAC \NWC"5;
"S \NAC"
BN"0"134;
%"TAP"
"3","(-4250,3225)","0","mstr_standard","I419";
;
CDS_LIB"mstr_standard"
BODY_TYPE"PLUMBING"
HDL_TAP"TRUE";
"B \NAC \NWC"6;
"S \NAC"
BN"0"78;
%"TAP"
"3","(-4450,3225)","0","mstr_standard","I420";
;
CDS_LIB"mstr_standard"
BODY_TYPE"PLUMBING"
HDL_TAP"TRUE";
"B \NAC \NWC"6;
"S \NAC"
BN"1"133;
%"TAP"
"7","(-4500,3425)","0","mstr_standard","I421";
;
CDS_LIB"mstr_standard"
BODY_TYPE"PLUMBING"
HDL_TAP"TRUE";
"B \NAC \NWC"5;
"S \NAC"
BN"1"79;
%"TAP"
"3","(-4650,3225)","0","mstr_standard","I425";
;
CDS_LIB"mstr_standard"
BODY_TYPE"PLUMBING"
HDL_TAP"TRUE";
"B \NAC \NWC"6;
"S \NAC"
BN"2"131;
%"TAP"
"7","(-4700,3425)","0","mstr_standard","I426";
;
CDS_LIB"mstr_standard"
BODY_TYPE"PLUMBING"
HDL_TAP"TRUE";
"B \NAC \NWC"5;
"S \NAC"
BN"2"128;
%"TAP"
"3","(-4850,3225)","0","mstr_standard","I428";
;
CDS_LIB"mstr_standard"
BODY_TYPE"PLUMBING"
HDL_TAP"TRUE";
"B \NAC \NWC"6;
"S \NAC"
BN"3"132;
%"TAP"
"7","(-4900,3425)","0","mstr_standard","I429";
;
CDS_LIB"mstr_standard"
BODY_TYPE"PLUMBING"
HDL_TAP"TRUE";
"B \NAC \NWC"5;
"S \NAC"
BN"3"117;
%"TAP"
"7","(-4250,2425)","0","mstr_standard","I430";
;
CDS_LIB"mstr_standard"
BODY_TYPE"PLUMBING"
HDL_TAP"TRUE";
"B \NAC \NWC"9;
"S \NAC"
BN"0"81;
%"TAP"
"7","(-4450,2425)","0","mstr_standard","I432";
;
CDS_LIB"mstr_standard"
BODY_TYPE"PLUMBING"
HDL_TAP"TRUE";
"B \NAC \NWC"9;
"S \NAC"
BN"1"80;
%"TAP"
"7","(-4650,2425)","0","mstr_standard","I434";
;
CDS_LIB"mstr_standard"
BODY_TYPE"PLUMBING"
HDL_TAP"TRUE";
"B \NAC \NWC"9;
"S \NAC"
BN"2"82;
%"TAP"
"7","(-4850,2425)","0","mstr_standard","I436";
;
CDS_LIB"mstr_standard"
BODY_TYPE"PLUMBING"
HDL_TAP"TRUE";
"B \NAC \NWC"9;
"S \NAC"
BN"3"83;
%"TAP"
"7","(-5100,3425)","0","mstr_standard","I440";
;
CDS_LIB"mstr_standard"
BODY_TYPE"PLUMBING"
HDL_TAP"TRUE";
"B \NAC \NWC"5;
"S \NAC"
BN"4"44;
%"TAP"
"3","(-5050,3225)","0","mstr_standard","I441";
;
CDS_LIB"mstr_standard"
BODY_TYPE"PLUMBING"
HDL_TAP"TRUE";
"B \NAC \NWC"6;
"S \NAC"
BN"4"84;
%"TAP"
"7","(-5300,3425)","0","mstr_standard","I442";
;
CDS_LIB"mstr_standard"
BODY_TYPE"PLUMBING"
HDL_TAP"TRUE";
"B \NAC \NWC"5;
"S \NAC"
BN"5"47;
%"TAP"
"3","(-5250,3225)","0","mstr_standard","I443";
;
CDS_LIB"mstr_standard"
BODY_TYPE"PLUMBING"
HDL_TAP"TRUE";
"B \NAC \NWC"6;
"S \NAC"
BN"5"85;
%"TAP"
"7","(-5500,3425)","0","mstr_standard","I445";
;
CDS_LIB"mstr_standard"
BODY_TYPE"PLUMBING"
HDL_TAP"TRUE";
"B \NAC \NWC"5;
"S \NAC"
BN"6"118;
%"TAP"
"3","(-5450,3225)","0","mstr_standard","I446";
;
CDS_LIB"mstr_standard"
BODY_TYPE"PLUMBING"
HDL_TAP"TRUE";
"B \NAC \NWC"6;
"S \NAC"
BN"6"87;
%"TAP"
"3","(-5650,3225)","0","mstr_standard","I449";
;
CDS_LIB"mstr_standard"
BODY_TYPE"PLUMBING"
HDL_TAP"TRUE";
"B \NAC \NWC"6;
"S \NAC"
BN"7"125;
%"TAP"
"7","(-5700,3425)","0","mstr_standard","I450";
;
CDS_LIB"mstr_standard"
BODY_TYPE"PLUMBING"
HDL_TAP"TRUE";
"B \NAC \NWC"5;
"S \NAC"
BN"7"48;
%"TAP"
"7","(-5050,2425)","0","mstr_standard","I451";
;
CDS_LIB"mstr_standard"
BODY_TYPE"PLUMBING"
HDL_TAP"TRUE";
"B \NAC \NWC"9;
"S \NAC"
BN"4"126;
%"TAP"
"7","(-5250,2425)","0","mstr_standard","I453";
;
CDS_LIB"mstr_standard"
BODY_TYPE"PLUMBING"
HDL_TAP"TRUE";
"B \NAC \NWC"9;
"S \NAC"
BN"5"86;
%"TAP"
"7","(-5650,2425)","0","mstr_standard","I454";
;
CDS_LIB"mstr_standard"
BODY_TYPE"PLUMBING"
HDL_TAP"TRUE";
"B \NAC \NWC"9;
"S \NAC"
BN"7"89;
%"CAP"
"1","(-5700,3675)","0","mstr_discrete","I474";
;
CDS_SEC"1"
$SEC"1"
CDS_LOCATION"C3P41"
GROUP"PCIE_RISER"
VOLTAGE"16V"
VALUE"0.22UF"
TOLERANCE"10%"
PACK_TYPE"0402"
PART_NUMBER"A36096-155"
MATERIAL"X7R"
LOCATION"C3P41"
CDS_LIB"mstr_discrete";
"A"
$PN"1"119;
"B"
$PN"2"48;
%"CAP"
"1","(-5500,3975)","0","mstr_discrete","I475";
;
CDS_SEC"1"
$SEC"1"
CDS_LOCATION"C3P36"
GROUP"PCIE_RISER"
VOLTAGE"16V"
TOLERANCE"10%"
PACK_TYPE"0402"
MATERIAL"X7R"
VALUE"0.22UF"
LOCATION"C3P36"
PART_NUMBER"A36096-155"
CDS_LIB"mstr_discrete";
"A"
$PN"1"46;
"B"
$PN"2"118;
%"CAP"
"1","(-4500,3700)","0","mstr_discrete","I476";
;
CDS_SEC"1"
$SEC"1"
CDS_LOCATION"C3P16"
VALUE"0.22UF"
MATERIAL"X7R"
PART_NUMBER"A36096-155"
PACK_TYPE"0402"
GROUP"PCIE_RISER"
VOLTAGE"16V"
TOLERANCE"10%"
LOCATION"C3P16"
CDS_LIB"mstr_discrete";
"A"
$PN"1"24;
"B"
$PN"2"79;
%"CAP"
"1","(-5300,3675)","0","mstr_discrete","I477";
;
CDS_SEC"1"
$SEC"1"
CDS_LOCATION"C3P33"
GROUP"PCIE_RISER"
PART_NUMBER"A36096-155"
VALUE"0.22UF"
VOLTAGE"16V"
TOLERANCE"10%"
PACK_TYPE"0402"
LOCATION"C3P33"
MATERIAL"X7R"
CDS_LIB"mstr_discrete";
"A"
$PN"1"76;
"B"
$PN"2"47;
%"CAP"
"1","(-5100,3975)","0","mstr_discrete","I478";
;
CDS_SEC"1"
$SEC"1"
CDS_LOCATION"C3P29"
GROUP"PCIE_RISER"
TOLERANCE"10%"
VALUE"0.22UF"
VOLTAGE"16V"
MATERIAL"X7R"
PACK_TYPE"0402"
LOCATION"C3P29"
PART_NUMBER"A36096-155"
CDS_LIB"mstr_discrete";
"A"
$PN"1"45;
"B"
$PN"2"44;
%"CAP"
"1","(-4900,3675)","0","mstr_discrete","I479";
;
CDS_SEC"1"
$SEC"1"
CDS_LOCATION"C3P24"
GROUP"PCIE_RISER"
LOCATION"C3P24"
VALUE"0.22UF"
VOLTAGE"16V"
TOLERANCE"10%"
MATERIAL"X7R"
PART_NUMBER"A36096-155"
PACK_TYPE"0402"
CDS_LIB"mstr_discrete";
"A"
$PN"1"77;
"B"
$PN"2"117;
%"CAP"
"1","(-4700,3975)","0","mstr_discrete","I480";
;
CDS_SEC"1"
$SEC"1"
CDS_LOCATION"C3P21"
LOCATION"C3P21"
GROUP"PCIE_RISER"
PART_NUMBER"A36096-155"
MATERIAL"X7R"
PACK_TYPE"0402"
VALUE"0.22UF"
VOLTAGE"16V"
TOLERANCE"10%"
CDS_LIB"mstr_discrete";
"A"
$PN"1"43;
"B"
$PN"2"128;
%"CAP"
"1","(-4300,3975)","0","mstr_discrete","I481";
;
CDS_SEC"1"
$SEC"1"
CDS_LOCATION"C3P12"
GROUP"PCIE_RISER"
VALUE"0.22UF"
TOLERANCE"10%"
MATERIAL"X7R"
PART_NUMBER"A36096-155"
PACK_TYPE"0402"
VOLTAGE"16V"
LOCATION"C3P12"
CDS_LIB"mstr_discrete";
"A"
$PN"1"42;
"B"
$PN"2"134;
%"CAP"
"1","(-4250,2975)","0","mstr_discrete","I482";
;
CDS_SEC"1"
$SEC"1"
CDS_LOCATION"C3P10"
GROUP"PCIE_RISER"
LOCATION"C3P10"
VALUE"0.22UF"
MATERIAL"X7R"
TOLERANCE"10%"
VOLTAGE"16V"
PACK_TYPE"0402"
PART_NUMBER"A36096-155"
CDS_LIB"mstr_discrete";
"A"
$PN"1"78;
"B"
$PN"2"81;
%"CAP"
"1","(-4450,2675)","0","mstr_discrete","I483";
;
CDS_SEC"1"
$SEC"1"
CDS_LOCATION"C3P14"
GROUP"PCIE_RISER"
LOCATION"C3P14"
VALUE"0.22UF"
VOLTAGE"16V"
PART_NUMBER"A36096-155"
PACK_TYPE"0402"
MATERIAL"X7R"
TOLERANCE"10%"
CDS_LIB"mstr_discrete";
"A"
$PN"1"133;
"B"
$PN"2"80;
%"CAP"
"1","(-4850,2675)","0","mstr_discrete","I484";
;
CDS_SEC"1"
$SEC"1"
CDS_LOCATION"C3P22"
GROUP"PCIE_RISER"
MATERIAL"X7R"
VALUE"0.22UF"
LOCATION"C3P22"
VOLTAGE"16V"
TOLERANCE"10%"
PACK_TYPE"0402"
PART_NUMBER"A36096-155"
CDS_LIB"mstr_discrete";
"A"
$PN"1"132;
"B"
$PN"2"83;
%"CAP"
"1","(-4650,2975)","0","mstr_discrete","I485";
;
CDS_SEC"1"
$SEC"1"
CDS_LOCATION"C3P19"
GROUP"PCIE_RISER"
LOCATION"C3P19"
VALUE"0.22UF"
MATERIAL"X7R"
TOLERANCE"10%"
VOLTAGE"16V"
PART_NUMBER"A36096-155"
PACK_TYPE"0402"
CDS_LIB"mstr_discrete";
"A"
$PN"1"131;
"B"
$PN"2"82;
%"CAP"
"1","(-5650,2675)","0","mstr_discrete","I486";
;
CDS_SEC"1"
$SEC"1"
CDS_LOCATION"C3P38"
GROUP"PCIE_RISER"
VALUE"0.22UF"
VOLTAGE"16V"
TOLERANCE"10%"
MATERIAL"X7R"
PACK_TYPE"0402"
PART_NUMBER"A36096-155"
LOCATION"C3P38"
CDS_LIB"mstr_discrete";
"A"
$PN"1"125;
"B"
$PN"2"89;
%"CAP"
"1","(-5050,2975)","0","mstr_discrete","I487";
;
CDS_SEC"1"
$SEC"1"
CDS_LOCATION"C3P26"
GROUP"PCIE_RISER"
MATERIAL"X7R"
LOCATION"C3P26"
PART_NUMBER"A36096-155"
PACK_TYPE"0402"
TOLERANCE"10%"
VOLTAGE"16V"
VALUE"0.22UF"
CDS_LIB"mstr_discrete";
"A"
$PN"1"84;
"B"
$PN"2"126;
%"CAP"
"1","(-5250,2675)","0","mstr_discrete","I488";
;
CDS_SEC"1"
$SEC"1"
CDS_LOCATION"C3P31"
GROUP"PCIE_RISER"
LOCATION"C3P31"
VALUE"0.22UF"
VOLTAGE"16V"
TOLERANCE"10%"
MATERIAL"X7R"
PART_NUMBER"A36096-155"
PACK_TYPE"0402"
CDS_LIB"mstr_discrete";
"A"
$PN"1"85;
"B"
$PN"2"86;
%"CAP"
"1","(-5450,2975)","0","mstr_discrete","I489";
;
CDS_SEC"1"
$SEC"1"
CDS_LOCATION"C3P34"
GROUP"PCIE_RISER"
PART_NUMBER"A36096-155"
PACK_TYPE"0402"
MATERIAL"X7R"
TOLERANCE"10%"
VALUE"0.22UF"
LOCATION"C3P34"
VOLTAGE"16V"
CDS_LIB"mstr_discrete";
"A"
$PN"1"87;
"B"
$PN"2"88;
%"RES"
"1","(-825,4125)","1","mstr_discrete","I490";
;
CDS_SEC"1"
$SEC"1"
CDS_LOCATION"R2U15"
VALUE"0.0"
PACK_TYPE"0402"
WATTAGE"1/16W"
TOLERANCE"5%"
PART_NUMBER"G21497-005"
MATERIAL"CHIP"
LOCATION"R2U15"
GROUP"PCIE_RISER"
CDS_LIB"mstr_discrete";
"B"
$PN"2"25;
"A"
$PN"1"122;
%"RES"
"1","(-1425,3825)","1","mstr_discrete","I491";
;
CDS_SEC"1"
$SEC"1"
CDS_LOCATION"R2U21"
TOLERANCE"5%"
WATTAGE"1/16W"
PACK_TYPE"0402"
PART_NUMBER"G21497-005"
VALUE"0.0"
MATERIAL"CHIP"
LOCATION"R2U21"
GROUP"PCIE_RISER"
CDS_LIB"mstr_discrete";
"B"
$PN"2"40;
"A"
$PN"1"39;
%"RES"
"1","(-1025,3825)","1","mstr_discrete","I492";
;
CDS_SEC"1"
$SEC"1"
CDS_LOCATION"R2U17"
GROUP"PCIE_RISER"
PART_NUMBER"G21497-005"
PACK_TYPE"0402"
WATTAGE"1/16W"
TOLERANCE"5%"
LOCATION"R2U17"
MATERIAL"CHIP"
VALUE"0.0"
CDS_LIB"mstr_discrete";
"B"
$PN"2"26;
"A"
$PN"1"90;
%"RES"
"1","(-1225,4125)","1","mstr_discrete","I493";
;
CDS_SEC"1"
$SEC"1"
CDS_LOCATION"R2U19"
LOCATION"R2U19"
PART_NUMBER"G21497-005"
VALUE"0.0"
PACK_TYPE"0402"
MATERIAL"CHIP"
WATTAGE"1/16W"
TOLERANCE"5%"
GROUP"PCIE_RISER"
CDS_LIB"mstr_discrete";
"B"
$PN"2"41;
"A"
$PN"1"27;
%"RES"
"1","(-2225,3825)","1","mstr_discrete","I494";
;
CDS_SEC"1"
$SEC"1"
CDS_LOCATION"R2U29"
GROUP"PCIE_RISER"
WATTAGE"1/16W"
TOLERANCE"5%"
MATERIAL"CHIP"
PACK_TYPE"0402"
VALUE"0.0"
PART_NUMBER"G21497-005"
LOCATION"R2U29"
CDS_LIB"mstr_discrete";
"B"
$PN"2"121;
"A"
$PN"1"37;
%"RES"
"1","(-1625,4125)","1","mstr_discrete","I495";
;
CDS_SEC"1"
$SEC"1"
CDS_LOCATION"R2U23"
TOLERANCE"5%"
WATTAGE"1/16W"
MATERIAL"CHIP"
PART_NUMBER"G21497-005"
LOCATION"R2U23"
VALUE"0.0"
PACK_TYPE"0402"
GROUP"PCIE_RISER"
CDS_LIB"mstr_discrete";
"B"
$PN"2"29;
"A"
$PN"1"130;
%"RES"
"1","(-1825,3825)","1","mstr_discrete","I496";
;
CDS_SEC"1"
$SEC"1"
CDS_LOCATION"R2U25"
TOLERANCE"5%"
WATTAGE"1/16W"
MATERIAL"CHIP"
PART_NUMBER"G21497-005"
PACK_TYPE"0402"
VALUE"0.0"
LOCATION"R2U25"
GROUP"PCIE_RISER"
CDS_LIB"mstr_discrete";
"B"
$PN"2"28;
"A"
$PN"1"129;
%"RES"
"1","(-2025,4125)","1","mstr_discrete","I497";
;
CDS_SEC"1"
$SEC"1"
CDS_LOCATION"R2U27"
GROUP"PCIE_RISER"
VALUE"0.0"
PACK_TYPE"0402"
MATERIAL"CHIP"
WATTAGE"1/16W"
TOLERANCE"5%"
LOCATION"R2U27"
PART_NUMBER"G21497-005"
CDS_LIB"mstr_discrete";
"B"
$PN"2"38;
"A"
$PN"1"91;
%"RES"
"1","(-2000,3100)","1","mstr_discrete","I498";
;
CDS_SEC"1"
$SEC"1"
CDS_LOCATION"R2U26"
GROUP"PCIE_RISER"
TOLERANCE"5%"
LOCATION"R2U26"
WATTAGE"1/16W"
PACK_TYPE"0402"
MATERIAL"CHIP"
VALUE"0.0"
PART_NUMBER"G21497-005"
CDS_LIB"mstr_discrete";
"B"
$PN"2"31;
"A"
$PN"1"120;
%"RES"
"1","(-800,3100)","1","mstr_discrete","I499";
;
CDS_SEC"1"
$SEC"1"
CDS_LOCATION"R2U14"
GROUP"PCIE_RISER"
LOCATION"R2U14"
VALUE"0.0"
TOLERANCE"5%"
WATTAGE"1/16W"
PART_NUMBER"G21497-005"
PACK_TYPE"0402"
MATERIAL"CHIP"
CDS_LIB"mstr_discrete";
"B"
$PN"2"36;
"A"
$PN"1"113;
%"RES"
"1","(-2200,2800)","1","mstr_discrete","I500";
;
CDS_SEC"1"
$SEC"1"
CDS_LOCATION"R2U28"
GROUP"PCIE_RISER"
PART_NUMBER"G21497-005"
PACK_TYPE"0402"
MATERIAL"CHIP"
LOCATION"R2U28"
WATTAGE"1/16W"
TOLERANCE"5%"
VALUE"0.0"
CDS_LIB"mstr_discrete";
"B"
$PN"2"127;
"A"
$PN"1"92;
%"RES"
"1","(-1000,2800)","1","mstr_discrete","I501";
;
CDS_SEC"1"
$SEC"1"
CDS_LOCATION"R2U16"
GROUP"PCIE_RISER"
LOCATION"R2U16"
VALUE"0.0"
TOLERANCE"5%"
WATTAGE"1/16W"
MATERIAL"CHIP"
PACK_TYPE"0402"
PART_NUMBER"G21497-005"
CDS_LIB"mstr_discrete";
"B"
$PN"2"124;
"A"
$PN"1"35;
%"RES"
"1","(-1200,3100)","1","mstr_discrete","I502";
;
CDS_SEC"1"
$SEC"1"
CDS_LOCATION"R2U18"
GROUP"PCIE_RISER"
PART_NUMBER"G21497-005"
LOCATION"R2U18"
TOLERANCE"5%"
WATTAGE"1/16W"
MATERIAL"CHIP"
VALUE"0.0"
PACK_TYPE"0402"
CDS_LIB"mstr_discrete";
"B"
$PN"2"30;
"A"
$PN"1"123;
%"RES"
"1","(-1400,2800)","1","mstr_discrete","I503";
;
CDS_SEC"1"
$SEC"1"
CDS_LOCATION"R2U20"
GROUP"PCIE_RISER"
PART_NUMBER"G21497-005"
PACK_TYPE"0402"
MATERIAL"CHIP"
WATTAGE"1/16W"
TOLERANCE"5%"
VALUE"0.0"
LOCATION"R2U20"
CDS_LIB"mstr_discrete";
"B"
$PN"2"116;
"A"
$PN"1"34;
%"RES"
"1","(-1600,3100)","1","mstr_discrete","I504";
;
CDS_SEC"1"
$SEC"1"
CDS_LOCATION"R2U22"
GROUP"PCIE_RISER"
TOLERANCE"5%"
WATTAGE"1/16W"
VALUE"0.0"
MATERIAL"CHIP"
LOCATION"R2U22"
PACK_TYPE"0402"
PART_NUMBER"G21497-005"
CDS_LIB"mstr_discrete";
"B"
$PN"2"33;
"A"
$PN"1"114;
%"RES"
"1","(-1800,2800)","1","mstr_discrete","I505";
;
CDS_SEC"1"
$SEC"1"
CDS_LOCATION"R2U24"
GROUP"PCIE_RISER"
MATERIAL"CHIP"
PACK_TYPE"0402"
TOLERANCE"5%"
WATTAGE"1/16W"
PART_NUMBER"G21497-005"
VALUE"0.0"
LOCATION"R2U24"
CDS_LIB"mstr_discrete";
"B"
$PN"2"115;
"A"
$PN"1"32;
END.
